# T6G (Grand Teton) — schematic netlist excerpt (pin names and nets, part order shuffled) for the footprints in the layout excerpt that follows; sources: Cadence DE-HDL packaged netlist, KiCad conversion of 04192023_DAF0TMB3IC0_F0TG_MB_C_brd_V02_OCP.brd

R4569  Q_RES  0 5% EMPTY  pkg 0402LF  page 124 : A = GPU_3V3IO_RSVD1 ; B = GPU_3V3IO_RSVD1_ISO
C6656  Q_CAP_DIFFBUS  DIFF BUS_0.22UF 6.3V 20% X6S  pkg C0201  page 319 : \1\ = P5E_CPU1_P0_TX_BUF_C_DN<13> ; \2\ = P5E_CPU1_P0_TX_BUF_DN<13>
PD113  SCHOTTKY_AC  B340A-13-F IC  pkg D2010XF  page 146 : A = GND ; C = P3V3_E1S_0_R

(kicad_pcb
	(version 20260206)
	(generator "pcbnew")
	(generator_version "10.0")
	(general
		(thickness 1.6)
		(legacy_teardrops no)
	)
	(paper "A4")
	(title_block
		(title "04192023_DAF0TMB3IC0_F0TG_MB_C_brd_V02_OCP.brd")
		(comment 1 "Grand Teton / footprints 4416-4418 of 8354")
	)
	(layers
		(0 "F.Cu" signal "TOP")
		(4 "In1.Cu" signal "GND")
		(6 "In2.Cu" signal "IN1")
		(8 "In3.Cu" signal "GND1")
		(10 "In4.Cu" signal "IN2")
		(12 "In5.Cu" signal "GND2")
		(14 "In6.Cu" signal "IN3")
		(16 "In7.Cu" signal "GND3")
		(18 "In8.Cu" signal "VCC")
		(20 "In9.Cu" signal "VCC1")
		(22 "In10.Cu" signal "GND4")
		(24 "In11.Cu" signal "IN4")
		(26 "In12.Cu" signal "GND5")
		(28 "In13.Cu" signal "IN5")
		(30 "In14.Cu" signal "GND6")
		(32 "In15.Cu" signal "IN6")
		(34 "In16.Cu" signal "GND7")
		(2 "B.Cu" signal "BOTTOM")
		(9 "F.Adhes" user "F.Adhesive")
		(11 "B.Adhes" user "B.Adhesive")
		(13 "F.Paste" user "Package Geometry/Pastemask Top")
		(15 "B.Paste" user "Package Geometry/Pastemask Bottom")
		(5 "F.SilkS" user "Ref Des/Silkscreen Top")
		(7 "B.SilkS" user "Ref Des/Silkscreen Bottom")
		(1 "F.Mask" user "Board Geometry/Soldermask Top")
		(3 "B.Mask" user "Board Geometry/Soldermask Bottom")
		(17 "Dwgs.User" user "User.Drawings")
		(19 "Cmts.User" user "User.Comments")
		(21 "Eco1.User" user "User.Eco1")
		(23 "Eco2.User" user "User.Eco2")
		(25 "Edge.Cuts" user "Board Geometry/Outline")
		(27 "Margin" user)
		(31 "F.CrtYd" user "Package Geometry/Place Bound Top")
		(29 "B.CrtYd" user "Package Geometry/Place Bound Bottom")
		(35 "F.Fab" user "Ref Des/Assembly Top")
		(33 "B.Fab" user "Ref Des/Assembly Bottom")
	)
	(footprint ""
		(layer "F.Cu")
		(at 421.262302 -435.186836 -90)
		(property "Reference" "R4569"
			(at 0 0 270)
			(layer "F.SilkS")
			(hide yes)
			(effects
				(font
					(size 1.27 1.27)
				)
			)
		)
		(property "Value" ""
			(at 0 0 270)
			(layer "F.Fab")
			(effects
				(font
					(size 1.27 1.27)
				)
			)
		)
		(duplicate_pad_numbers_are_jumpers no)
		(fp_line
			(start -0.7874 0.4064)
			(end -0.7874 -0.4064)
			(stroke
				(width 0.1524)
				(type default)
			)
			(layer "F.SilkS")
		)
		(fp_line
			(start 0.7874 0.4064)
			(end -0.7874 0.4064)
			(stroke
				(width 0.1524)
				(type default)
			)
			(layer "F.SilkS")
		)
		(fp_line
			(start -0.7874 -0.4064)
			(end 0.7874 -0.4064)
			(stroke
				(width 0.1524)
				(type default)
			)
			(layer "F.SilkS")
		)
		(fp_line
			(start 0.7874 -0.4064)
			(end 0.7874 0.4064)
			(stroke
				(width 0.1524)
				(type default)
			)
			(layer "F.SilkS")
		)
		(fp_line
			(start -0.67945 0.3048)
			(end -0.67945 -0.305054)
			(stroke
				(width 0.1)
				(type default)
			)
			(layer "F.Fab")
		)
		(fp_line
			(start -0.12065 0.3048)
			(end -0.67945 0.3048)
			(stroke
				(width 0.1)
				(type default)
			)
			(layer "F.Fab")
		)
		(fp_line
			(start 0.120396 0.3048)
			(end 0.120396 0.2794)
			(stroke
				(width 0.1)
				(type default)
			)
			(layer "F.Fab")
		)
		(fp_line
			(start 0.67945 0.3048)
			(end 0.120396 0.3048)
			(stroke
				(width 0.1)
				(type default)
			)
			(layer "F.Fab")
		)
		(fp_line
			(start -0.12065 0.2794)
			(end -0.12065 0.3048)
			(stroke
				(width 0.1)
				(type default)
			)
			(layer "F.Fab")
		)
		(fp_line
			(start 0.120396 0.2794)
			(end -0.12065 0.2794)
			(stroke
				(width 0.1)
				(type default)
			)
			(layer "F.Fab")
		)
		(fp_line
			(start -0.12065 -0.2794)
			(end 0.12065 -0.2794)
			(stroke
				(width 0.1)
				(type default)
			)
			(layer "F.Fab")
		)
		(fp_line
			(start 0.12065 -0.2794)
			(end 0.12065 -0.3048)
			(stroke
				(width 0.1)
				(type default)
			)
			(layer "F.Fab")
		)
		(fp_line
			(start 0.12065 -0.3048)
			(end 0.67945 -0.3048)
			(stroke
				(width 0.1)
				(type default)
			)
			(layer "F.Fab")
		)
		(fp_line
			(start 0.67945 -0.3048)
			(end 0.67945 0.3048)
			(stroke
				(width 0.1)
				(type default)
			)
			(layer "F.Fab")
		)
		(fp_line
			(start -0.67945 -0.305054)
			(end -0.12065 -0.305054)
			(stroke
				(width 0.1)
				(type default)
			)
			(layer "F.Fab")
		)
		(fp_line
			(start -0.12065 -0.305054)
			(end -0.12065 -0.2794)
			(stroke
				(width 0.1)
				(type default)
			)
			(layer "F.Fab")
		)
		(pad "1" smd circle
			(at -0.40005 0 270)
			(size 0 0)
			(layers "F.Cu" "F.Mask" "F.Paste")
			(net "GPU_3V3IO_RSVD1")
		)
		(pad "2" smd circle
			(at 0.40005 0 270)
			(size 0 0)
			(layers "F.Cu" "F.Mask" "F.Paste")
			(net "GPU_3V3IO_RSVD1_ISO")
		)
	)
	(footprint ""
		(layer "F.Cu")
		(at 87.590884 -408.517344 -90)
		(property "Reference" "C6656"
			(at 0 0 270)
			(layer "F.SilkS")
			(hide yes)
			(effects
				(font
					(size 1.27 1.27)
				)
			)
		)
		(property "Value" ""
			(at 0 0 270)
			(layer "F.Fab")
			(effects
				(font
					(size 1.27 1.27)
				)
			)
		)
		(duplicate_pad_numbers_are_jumpers no)
		(fp_line
			(start -0.299974 0.150114)
			(end -0.299974 -0.150114)
			(stroke
				(width 0.1)
				(type default)
			)
			(layer "F.Fab")
		)
		(fp_line
			(start 0.299974 0.150114)
			(end -0.299974 0.150114)
			(stroke
				(width 0.1)
				(type default)
			)
			(layer "F.Fab")
		)
		(fp_line
			(start -0.299974 -0.150114)
			(end 0.299974 -0.150114)
			(stroke
				(width 0.1)
				(type default)
			)
			(layer "F.Fab")
		)
		(fp_line
			(start 0.299974 -0.150114)
			(end 0.299974 0.150114)
			(stroke
				(width 0.1)
				(type default)
			)
			(layer "F.Fab")
		)
		(pad "1" smd rect
			(at -0.2667 0 270)
			(size 0.3048 0.381)
			(layers "F.Cu" "F.Mask" "F.Paste")
			(net "P5E_CPU1_P0_TX_BUF_C_DN<13>")
		)
		(pad "2" smd rect
			(at 0.2667 0 270)
			(size 0.3048 0.381)
			(layers "F.Cu" "F.Mask" "F.Paste")
			(net "P5E_CPU1_P0_TX_BUF_DN<13>")
		)
	)
	(footprint ""
		(layer "F.Cu")
		(at 214.973408 -67.220084 -90)
		(property "Reference" "PD113"
			(at 3.924808 2.193544 90)
			(unlocked yes)
			(layer "F.SilkS")
			(effects
				(font
					(size 0.7874 0.5842)
					(thickness 0.1524)
				)
				(justify left)
			)
		)
		(property "Value" ""
			(at 0 0 270)
			(layer "F.Fab")
			(effects
				(font
					(size 1.27 1.27)
				)
			)
		)
		(duplicate_pad_numbers_are_jumpers no)
		(fp_line
			(start -3.400044 1.459992)
			(end -3.400044 -1.459992)
			(stroke
				(width 0.1524)
				(type default)
			)
			(layer "F.SilkS")
		)
		(fp_line
			(start 4.107942 1.459992)
			(end -3.400044 1.459992)
			(stroke
				(width 0.1524)
				(type default)
			)
			(layer "F.SilkS")
		)
		(fp_line
			(start -3.400044 -1.459992)
			(end 4.107942 -1.459992)
			(stroke
				(width 0.1524)
				(type default)
			)
			(layer "F.SilkS")
		)
		(fp_line
			(start 4.107942 -1.459992)
			(end 4.107942 1.459992)
			(stroke
				(width 0.1524)
				(type default)
			)
			(layer "F.SilkS")
		)
		(fp_rect
			(start 4.107942 1.459992)
			(end 3.308096 -1.459992)
			(stroke
				(width 0)
				(type default)
			)
			(fill yes)
			(layer "F.SilkS")
		)
		(fp_line
			(start -2.29997 1.459992)
			(end -2.29997 -1.459992)
			(stroke
				(width 0.1)
				(type default)
			)
			(layer "F.Fab")
		)
		(fp_line
			(start 2.29997 1.459992)
			(end -2.29997 1.459992)
			(stroke
				(width 0.1)
				(type default)
			)
			(layer "F.Fab")
		)
		(fp_line
			(start -2.29997 -1.459992)
			(end 2.29997 -1.459992)
			(stroke
				(width 0.1)
				(type default)
			)
			(layer "F.Fab")
		)
		(fp_line
			(start 2.29997 -1.459992)
			(end 2.29997 1.459992)
			(stroke
				(width 0.1)
				(type default)
			)
			(layer "F.Fab")
		)
		(fp_text user "+"
			(at -4.7752 -0.12065 270)
			(unlocked yes)
			(layer "F.SilkS")
			(effects
				(font
					(size 1.905 1.4224)
					(thickness 0.1524)
				)
				(justify left)
			)
		)
		(fp_text user "-"
			(at 4.545838 -1.956054 90)
			(unlocked yes)
			(layer "F.SilkS")
			(effects
				(font
					(size 1.905 1.4224)
					(thickness 0.1524)
				)
				(justify left)
			)
		)
		(fp_text user "-"
			(at 5.4102 0.29845 90)
			(unlocked yes)
			(layer "F.Fab")
			(effects
				(font
					(size 1.905 1.4224)
					(thickness 0.1524)
				)
				(justify left)
			)
		)
		(fp_text user "+"
			(at -4.7752 -0.12065 270)
			(unlocked yes)
			(layer "F.Fab")
			(effects
				(font
					(size 1.905 1.4224)
					(thickness 0.1524)
				)
				(justify left)
			)
		)
		(pad "A" smd rect
			(at -1.999996 0)
			(size 1.7018 2.5146)
			(layers "F.Cu" "F.Mask" "F.Paste")
			(net "GND")
		)
		(pad "C" smd rect
			(at 1.999996 0)
			(size 1.7018 2.5146)
			(layers "F.Cu" "F.Mask" "F.Paste")
			(net "P3V3_E1S_0_R")
		)
	)
)
